# TIMECARD (Time Appliance Project (Time Card)) — schematic netlist excerpt (pin names and nets, part order shuffled) for the footprints in the layout excerpt that follows; sources: Cadence DE-HDL packaged netlist, KiCad conversion of R4006-B0001-02_R01.brd

C304  CAPACITOR  0.1UF 25V 10%  pkg SMC_0402R_H022  page 33 : \1\ = UNNAMED_525_CAPACITOR_I16_1 ; \2\ = SG
R35  RESISTOR  100KOHM 1%  pkg SMC_0402R_H016  page 28 : \1\ = XP3R3V_RT ; \2\ = XP3R3V_AGND

(kicad_pcb
	(version 20260206)
	(generator "pcbnew")
	(generator_version "10.0")
	(general
		(thickness 1.6)
		(legacy_teardrops no)
	)
	(paper "A4")
	(title_block
		(title "timecard-production-celestica-r4006 — R4006-B0001-02_R01.brd")
		(comment 1 "Time Appliance Project (Time Card) / footprints 261-262 of 1113")
	)
	(layers
		(0 "F.Cu" signal "TOP")
		(4 "In1.Cu" signal "L02_GND1")
		(6 "In2.Cu" signal "L03_SIG1")
		(8 "In3.Cu" signal "L04_GND2")
		(10 "In4.Cu" signal "L05_VCC1")
		(12 "In5.Cu" signal "L06_VCC2")
		(14 "In6.Cu" signal "L07_GND3")
		(16 "In7.Cu" signal "L08_SIG2")
		(18 "In8.Cu" signal "L09_GND4")
		(2 "B.Cu" signal "BOTTOM")
		(9 "F.Adhes" user "F.Adhesive")
		(11 "B.Adhes" user "B.Adhesive")
		(13 "F.Paste" user "Package Geometry/Pastemask Top")
		(15 "B.Paste" user "Package Geometry/Pastemask Bottom")
		(5 "F.SilkS" user "Ref Des/Silkscreen Top")
		(7 "B.SilkS" user "Ref Des/Silkscreen Bottom")
		(1 "F.Mask" user "Board Geometry/Soldermask Top")
		(3 "B.Mask" user "Board Geometry/Soldermask Bottom")
		(17 "Dwgs.User" user "User.Drawings")
		(19 "Cmts.User" user "User.Comments")
		(21 "Eco1.User" user "User.Eco1")
		(23 "Eco2.User" user "User.Eco2")
		(25 "Edge.Cuts" user "Board Geometry/Outline")
		(27 "Margin" user)
		(31 "F.CrtYd" user "Package Geometry/Place Bound Top")
		(29 "B.CrtYd" user "Package Geometry/Place Bound Bottom")
		(35 "F.Fab" user "Ref Des/Assembly Top")
		(33 "B.Fab" user "Ref Des/Assembly Bottom")
	)
	(footprint ""
		(layer "F.Cu")
		(at 46.863 -77.216)
		(property "Reference" "C304"
			(at 3.175 0.16637 0)
			(unlocked yes)
			(layer "F.SilkS")
			(effects
				(font
					(size 0.7874 0.5842)
					(thickness 0.1524)
				)
			)
		)
		(property "Value" "VAL*"
			(at 0.0762 2.067306 0)
			(unlocked yes)
			(layer "F.Fab")
			(hide yes)
			(effects
				(font
					(size 0.7874 0.5842)
					(thickness 0.1524)
				)
			)
		)
		(property "Tolerance" "TOL*"
			(at 0.0762 3.032506 0)
			(unlocked yes)
			(layer "Cmts.User")
			(hide yes)
			(effects
				(font
					(size 0.7874 0.5842)
					(thickness 0.1524)
				)
			)
		)
		(property "User Part Number" "PARTNUM*"
			(at 0.1016 4.023106 0)
			(unlocked yes)
			(layer "Cmts.User")
			(hide yes)
			(effects
				(font
					(size 0.7874 0.5842)
					(thickness 0.1524)
				)
			)
		)
		(property "Device Type" "CAPACITOR-G105-0B104-EK,0.1UF,A"
			(at 0.0508 1.127506 0)
			(unlocked yes)
			(layer "F.Fab")
			(hide yes)
			(effects
				(font
					(size 0.7874 0.5842)
					(thickness 0.1524)
				)
			)
		)
		(duplicate_pad_numbers_are_jumpers no)
		(fp_line
			(start -1.143 -0.5588)
			(end -1.143 0.5588)
			(stroke
				(width 0.1)
				(type default)
			)
			(layer "F.SilkS")
		)
		(fp_line
			(start -1.143 0.5588)
			(end 1.143 0.5588)
			(stroke
				(width 0.1)
				(type default)
			)
			(layer "F.SilkS")
		)
		(fp_line
			(start 1.143 -0.5588)
			(end -1.143 -0.5588)
			(stroke
				(width 0.1)
				(type default)
			)
			(layer "F.SilkS")
		)
		(fp_line
			(start 1.143 0.5588)
			(end 1.143 -0.5588)
			(stroke
				(width 0.1)
				(type default)
			)
			(layer "F.SilkS")
		)
		(fp_poly
			(pts
				(xy -1.143 0.5588) (xy 1.143 0.5588) (xy 1.143 -0.5588) (xy -1.143 -0.5588)
			)
			(stroke
				(width 0)
				(type default)
			)
			(fill no)
			(layer "F.CrtYd")
		)
		(fp_line
			(start -0.508 -0.3048)
			(end -0.508 0.3048)
			(stroke
				(width 0.1)
				(type default)
			)
			(layer "F.Fab")
		)
		(fp_line
			(start -0.508 0.3048)
			(end 0.508 0.3048)
			(stroke
				(width 0.1)
				(type default)
			)
			(layer "F.Fab")
		)
		(fp_line
			(start 0.508 -0.3048)
			(end -0.508 -0.3048)
			(stroke
				(width 0.1)
				(type default)
			)
			(layer "F.Fab")
		)
		(fp_line
			(start 0.508 0.3048)
			(end 0.508 -0.3048)
			(stroke
				(width 0.1)
				(type default)
			)
			(layer "F.Fab")
		)
		(pad "1" smd rect
			(at -0.5334 0)
			(size 0.7112 0.6096)
			(layers "F.Cu" "F.Mask" "F.Paste")
			(net "UNNAMED_525_CAPACITOR_I16_1")
		)
		(pad "2" smd rect
			(at 0.5334 0)
			(size 0.7112 0.6096)
			(layers "F.Cu" "F.Mask" "F.Paste")
			(net "SG")
		)
		(zone
			(layer "F.Cu")
			(hatch none 0.5)
			(connect_pads
				(clearance 0)
			)
			(min_thickness 0.25)
			(keepout
				(tracks not_allowed)
				(vias allowed)
				(pads allowed)
				(copperpour not_allowed)
				(footprints allowed)
			)
			(placement
				(enabled no)
				(sheetname "")
			)
			(fill
				(thermal_gap 0.5)
				(thermal_bridge_width 0.5)
				(island_removal_mode 0)
			)
			(polygon
				(pts
					(xy 46.7868 -76.9112) (xy 46.9392 -76.9112) (xy 46.9392 -77.5208) (xy 46.7868 -77.5208)
				)
			)
		)
		(zone
			(layer "F.Cu")
			(hatch none 0.5)
			(connect_pads
				(clearance 0)
			)
			(min_thickness 0.25)
			(keepout
				(tracks allowed)
				(vias not_allowed)
				(pads allowed)
				(copperpour not_allowed)
				(footprints allowed)
			)
			(placement
				(enabled no)
				(sheetname "")
			)
			(fill
				(thermal_gap 0.5)
				(thermal_bridge_width 0.5)
				(island_removal_mode 0)
			)
			(polygon
				(pts
					(xy 46.7868 -76.9112) (xy 46.9392 -76.9112) (xy 46.9392 -77.5208) (xy 46.7868 -77.5208)
				)
			)
		)
	)
	(footprint ""
		(layer "F.Cu")
		(at 87.4522 -97.4598 -90)
		(property "Reference" "R35"
			(at 5.2578 5.87883 90)
			(unlocked yes)
			(layer "F.SilkS")
			(effects
				(font
					(size 0.7874 0.5842)
					(thickness 0.1524)
				)
			)
		)
		(property "Value" "VAL*"
			(at 0.02032 2.13233 270)
			(unlocked yes)
			(layer "F.Fab")
			(hide yes)
			(effects
				(font
					(size 0.7874 0.5842)
					(thickness 0.1524)
				)
			)
		)
		(property "Tolerance" "TOL*"
			(at 0.044704 3.05435 270)
			(unlocked yes)
			(layer "Cmts.User")
			(hide yes)
			(effects
				(font
					(size 0.7874 0.5842)
					(thickness 0.1524)
				)
			)
		)
		(property "User Part Number" "PARTNUM*"
			(at 0.02032 4.024884 270)
			(unlocked yes)
			(layer "Cmts.User")
			(hide yes)
			(effects
				(font
					(size 0.7874 0.5842)
					(thickness 0.1524)
				)
			)
		)
		(property "Device Type" "RESISTOR-G155-11003-01,100KOHMA"
			(at 0.008382 1.210564 270)
			(unlocked yes)
			(layer "F.Fab")
			(hide yes)
			(effects
				(font
					(size 0.7874 0.5842)
					(thickness 0.1524)
				)
			)
		)
		(duplicate_pad_numbers_are_jumpers no)
		(fp_line
			(start -1.143 0.5588)
			(end 1.143 0.5588)
			(stroke
				(width 0.1)
				(type default)
			)
			(layer "F.SilkS")
		)
		(fp_line
			(start 1.143 0.5588)
			(end 1.143 -0.5588)
			(stroke
				(width 0.1)
				(type default)
			)
			(layer "F.SilkS")
		)
		(fp_line
			(start -1.143 -0.5588)
			(end -1.143 0.5588)
			(stroke
				(width 0.1)
				(type default)
			)
			(layer "F.SilkS")
		)
		(fp_line
			(start 1.143 -0.5588)
			(end -1.143 -0.5588)
			(stroke
				(width 0.1)
				(type default)
			)
			(layer "F.SilkS")
		)
		(fp_rect
			(start 1.143 0.5588)
			(end -1.143 -0.5588)
			(stroke
				(width 0)
				(type default)
			)
			(fill no)
			(layer "F.CrtYd")
		)
		(fp_line
			(start -0.508 0.3048)
			(end 0.508 0.3048)
			(stroke
				(width 0.1)
				(type default)
			)
			(layer "F.Fab")
		)
		(fp_line
			(start 0.508 0.3048)
			(end 0.508 -0.3048)
			(stroke
				(width 0.1)
				(type default)
			)
			(layer "F.Fab")
		)
		(fp_line
			(start -0.508 -0.3048)
			(end -0.508 0.3048)
			(stroke
				(width 0.1)
				(type default)
			)
			(layer "F.Fab")
		)
		(fp_line
			(start 0.508 -0.3048)
			(end -0.508 -0.3048)
			(stroke
				(width 0.1)
				(type default)
			)
			(layer "F.Fab")
		)
		(pad "1" smd rect
			(at -0.5334 0 270)
			(size 0.7112 0.6096)
			(layers "F.Cu" "F.Mask" "F.Paste")
			(net "XP3R3V_RT")
		)
		(pad "2" smd rect
			(at 0.5334 0 270)
			(size 0.7112 0.6096)
			(layers "F.Cu" "F.Mask" "F.Paste")
			(net "XP3R3V_AGND")
		)
		(zone
			(layer "F.Cu")
			(hatch none 0.5)
			(connect_pads
				(clearance 0)
			)
			(min_thickness 0.25)
			(keepout
				(tracks allowed)
				(vias not_allowed)
				(pads allowed)
				(copperpour not_allowed)
				(footprints allowed)
			)
			(placement
				(enabled no)
				(sheetname "")
			)
			(fill
				(thermal_gap 0.5)
				(thermal_bridge_width 0.5)
				(island_removal_mode 0)
			)
			(polygon
				(pts
					(xy 87.1474 -97.3836) (xy 87.757 -97.3836) (xy 87.757 -97.536) (xy 87.1474 -97.536)
				)
			)
		)
	)
)
